(kicad_pcb
	(version 20260206)
	(generator "pcbnew")
	(generator_version "10.0")
	(general
		(thickness 1.6)
		(legacy_teardrops no)
	)
	(paper "A4")
	(title_block
		(title "12092022_DA0F0TMDCD0_F0T_Management_Board_D_brd_V3_OCP.brd")
		(comment 1 "Grand Teton / footprints 503-508 of 1440")
	)
	(layers
		(0 "F.Cu" signal "TOP")
		(4 "In1.Cu" signal "GND")
		(6 "In2.Cu" signal "IN1")
		(8 "In3.Cu" signal "GND1")
		(10 "In4.Cu" signal "IN2")
		(12 "In5.Cu" signal "VCC")
		(14 "In6.Cu" signal "VCC1")
		(16 "In7.Cu" signal "IN3")
		(18 "In8.Cu" signal "GND2")
		(20 "In9.Cu" signal "IN4")
		(22 "In10.Cu" signal "GND3")
		(2 "B.Cu" signal "BOTTOM")
		(9 "F.Adhes" user "F.Adhesive")
		(11 "B.Adhes" user "B.Adhesive")
		(13 "F.Paste" user "Package Geometry/Pastemask Top")
		(15 "B.Paste" user "Package Geometry/Pastemask Bottom")
		(5 "F.SilkS" user "Ref Des/Silkscreen Top")
		(7 "B.SilkS" user "Ref Des/Silkscreen Bottom")
		(1 "F.Mask" user "Board Geometry/Soldermask Top")
		(3 "B.Mask" user "Board Geometry/Soldermask Bottom")
		(17 "Dwgs.User" user "User.Drawings")
		(19 "Cmts.User" user "User.Comments")
		(21 "Eco1.User" user "User.Eco1")
		(23 "Eco2.User" user "User.Eco2")
		(25 "Edge.Cuts" user "Board Geometry/Outline")
		(27 "Margin" user)
		(31 "F.CrtYd" user "Package Geometry/Place Bound Top")
		(29 "B.CrtYd" user "Package Geometry/Place Bound Bottom")
		(35 "F.Fab" user "Ref Des/Assembly Top")
		(33 "B.Fab" user "Ref Des/Assembly Bottom")
	)
	(footprint ""
		(layer "F.Cu")
		(at 66.3702 -63.9572 90)
		(property "Reference" "R175"
			(at 0 0 90)
			(layer "F.SilkS")
			(hide yes)
			(effects
				(font
					(size 1.27 1.27)
				)
			)
		)
		(property "Value" ""
			(at 0 0 90)
			(layer "F.Fab")
			(effects
				(font
					(size 1.27 1.27)
				)
			)
		)
		(duplicate_pad_numbers_are_jumpers no)
		(fp_line
			(start 0.7874 -0.4064)
			(end 0.7874 0.4064)
			(stroke
				(width 0.1524)
				(type default)
			)
			(layer "F.SilkS")
		)
		(fp_line
			(start -0.7874 -0.4064)
			(end 0.7874 -0.4064)
			(stroke
				(width 0.1524)
				(type default)
			)
			(layer "F.SilkS")
		)
		(fp_line
			(start 0.7874 0.4064)
			(end -0.7874 0.4064)
			(stroke
				(width 0.1524)
				(type default)
			)
			(layer "F.SilkS")
		)
		(fp_line
			(start -0.7874 0.4064)
			(end -0.7874 -0.4064)
			(stroke
				(width 0.1524)
				(type default)
			)
			(layer "F.SilkS")
		)
		(fp_line
			(start -0.12065 -0.305054)
			(end -0.12065 -0.2794)
			(stroke
				(width 0.1)
				(type default)
			)
			(layer "F.Fab")
		)
		(fp_line
			(start -0.67945 -0.305054)
			(end -0.12065 -0.305054)
			(stroke
				(width 0.1)
				(type default)
			)
			(layer "F.Fab")
		)
		(fp_line
			(start 0.67945 -0.3048)
			(end 0.67945 0.3048)
			(stroke
				(width 0.1)
				(type default)
			)
			(layer "F.Fab")
		)
		(fp_line
			(start 0.12065 -0.3048)
			(end 0.67945 -0.3048)
			(stroke
				(width 0.1)
				(type default)
			)
			(layer "F.Fab")
		)
		(fp_line
			(start 0.12065 -0.2794)
			(end 0.12065 -0.3048)
			(stroke
				(width 0.1)
				(type default)
			)
			(layer "F.Fab")
		)
		(fp_line
			(start -0.12065 -0.2794)
			(end 0.12065 -0.2794)
			(stroke
				(width 0.1)
				(type default)
			)
			(layer "F.Fab")
		)
		(fp_line
			(start 0.120396 0.2794)
			(end -0.12065 0.2794)
			(stroke
				(width 0.1)
				(type default)
			)
			(layer "F.Fab")
		)
		(fp_line
			(start -0.12065 0.2794)
			(end -0.12065 0.3048)
			(stroke
				(width 0.1)
				(type default)
			)
			(layer "F.Fab")
		)
		(fp_line
			(start 0.67945 0.3048)
			(end 0.120396 0.3048)
			(stroke
				(width 0.1)
				(type default)
			)
			(layer "F.Fab")
		)
		(fp_line
			(start 0.120396 0.3048)
			(end 0.120396 0.2794)
			(stroke
				(width 0.1)
				(type default)
			)
			(layer "F.Fab")
		)
		(fp_line
			(start -0.12065 0.3048)
			(end -0.67945 0.3048)
			(stroke
				(width 0.1)
				(type default)
			)
			(layer "F.Fab")
		)
		(fp_line
			(start -0.67945 0.3048)
			(end -0.67945 -0.305054)
			(stroke
				(width 0.1)
				(type default)
			)
			(layer "F.Fab")
		)
		(pad "1" smd circle
			(at -0.40005 0 90)
			(size 0 0)
			(layers "F.Cu" "F.Mask" "F.Paste")
			(net "SPI_BMC_BIOS_ROM_MOSI")
		)
		(pad "2" smd circle
			(at 0.40005 0 90)
			(size 0 0)
			(layers "F.Cu" "F.Mask" "F.Paste")
			(net "SPI_BMC_BIOS_ROM_R_MOSI")
		)
	)
	(footprint ""
		(layer "F.Cu")
		(at 54.229 -96.012 90)
		(property "Reference" "R106"
			(at 0 0 90)
			(layer "F.SilkS")
			(hide yes)
			(effects
				(font
					(size 1.27 1.27)
				)
			)
		)
		(property "Value" ""
			(at 0 0 90)
			(layer "F.Fab")
			(effects
				(font
					(size 1.27 1.27)
				)
			)
		)
		(duplicate_pad_numbers_are_jumpers no)
		(fp_line
			(start 0.7874 -0.4064)
			(end 0.7874 0.4064)
			(stroke
				(width 0.1524)
				(type default)
			)
			(layer "F.SilkS")
		)
		(fp_line
			(start -0.7874 -0.4064)
			(end 0.7874 -0.4064)
			(stroke
				(width 0.1524)
				(type default)
			)
			(layer "F.SilkS")
		)
		(fp_line
			(start 0.7874 0.4064)
			(end -0.7874 0.4064)
			(stroke
				(width 0.1524)
				(type default)
			)
			(layer "F.SilkS")
		)
		(fp_line
			(start -0.7874 0.4064)
			(end -0.7874 -0.4064)
			(stroke
				(width 0.1524)
				(type default)
			)
			(layer "F.SilkS")
		)
		(fp_line
			(start -0.12065 -0.305054)
			(end -0.12065 -0.2794)
			(stroke
				(width 0.1)
				(type default)
			)
			(layer "F.Fab")
		)
		(fp_line
			(start -0.67945 -0.305054)
			(end -0.12065 -0.305054)
			(stroke
				(width 0.1)
				(type default)
			)
			(layer "F.Fab")
		)
		(fp_line
			(start 0.67945 -0.3048)
			(end 0.67945 0.3048)
			(stroke
				(width 0.1)
				(type default)
			)
			(layer "F.Fab")
		)
		(fp_line
			(start 0.12065 -0.3048)
			(end 0.67945 -0.3048)
			(stroke
				(width 0.1)
				(type default)
			)
			(layer "F.Fab")
		)
		(fp_line
			(start 0.12065 -0.2794)
			(end 0.12065 -0.3048)
			(stroke
				(width 0.1)
				(type default)
			)
			(layer "F.Fab")
		)
		(fp_line
			(start -0.12065 -0.2794)
			(end 0.12065 -0.2794)
			(stroke
				(width 0.1)
				(type default)
			)
			(layer "F.Fab")
		)
		(fp_line
			(start 0.120396 0.2794)
			(end -0.12065 0.2794)
			(stroke
				(width 0.1)
				(type default)
			)
			(layer "F.Fab")
		)
		(fp_line
			(start -0.12065 0.2794)
			(end -0.12065 0.3048)
			(stroke
				(width 0.1)
				(type default)
			)
			(layer "F.Fab")
		)
		(fp_line
			(start 0.67945 0.3048)
			(end 0.120396 0.3048)
			(stroke
				(width 0.1)
				(type default)
			)
			(layer "F.Fab")
		)
		(fp_line
			(start 0.120396 0.3048)
			(end 0.120396 0.2794)
			(stroke
				(width 0.1)
				(type default)
			)
			(layer "F.Fab")
		)
		(fp_line
			(start -0.12065 0.3048)
			(end -0.67945 0.3048)
			(stroke
				(width 0.1)
				(type default)
			)
			(layer "F.Fab")
		)
		(fp_line
			(start -0.67945 0.3048)
			(end -0.67945 -0.305054)
			(stroke
				(width 0.1)
				(type default)
			)
			(layer "F.Fab")
		)
		(pad "1" smd circle
			(at -0.40005 0 90)
			(size 0 0)
			(layers "F.Cu" "F.Mask" "F.Paste")
			(net "RST_BMC_SRST_N")
		)
		(pad "2" smd circle
			(at 0.40005 0 90)
			(size 0 0)
			(layers "F.Cu" "F.Mask" "F.Paste")
			(net "RST_BMC_EXTRST_R2_N")
		)
	)
	(footprint ""
		(layer "F.Cu")
		(at 7.239 -61.087 180)
		(property "Reference" "PC218"
			(at 0 0 180)
			(layer "F.SilkS")
			(hide yes)
			(effects
				(font
					(size 1.27 1.27)
				)
			)
		)
		(property "Value" ""
			(at 0 0 180)
			(layer "F.Fab")
			(effects
				(font
					(size 1.27 1.27)
				)
			)
		)
		(duplicate_pad_numbers_are_jumpers no)
		(fp_line
			(start 1.524 0.762)
			(end -1.524 0.762)
			(stroke
				(width 0.1524)
				(type default)
			)
			(layer "F.SilkS")
		)
		(fp_line
			(start 1.524 -0.762)
			(end 1.524 0.762)
			(stroke
				(width 0.1524)
				(type default)
			)
			(layer "F.SilkS")
		)
		(fp_line
			(start -1.524 0.762)
			(end -1.524 -0.762)
			(stroke
				(width 0.1524)
				(type default)
			)
			(layer "F.SilkS")
		)
		(fp_line
			(start -1.524 -0.762)
			(end 1.524 -0.762)
			(stroke
				(width 0.1524)
				(type default)
			)
			(layer "F.SilkS")
		)
		(fp_line
			(start 1.1049 0.724916)
			(end 1.1049 -0.724916)
			(stroke
				(width 0.1)
				(type default)
			)
			(layer "F.Fab")
		)
		(fp_line
			(start 1.1049 -0.724916)
			(end -1.1049 -0.724916)
			(stroke
				(width 0.1)
				(type default)
			)
			(layer "F.Fab")
		)
		(fp_line
			(start -1.1049 0.724916)
			(end 1.1049 0.724916)
			(stroke
				(width 0.1)
				(type default)
			)
			(layer "F.Fab")
		)
		(fp_line
			(start -1.1049 -0.724916)
			(end -1.1049 0.724916)
			(stroke
				(width 0.1)
				(type default)
			)
			(layer "F.Fab")
		)
		(pad "1" smd rect
			(at -0.889 0)
			(size 1.016 1.27)
			(layers "F.Cu" "F.Mask" "F.Paste")
			(net "SW_P3V3_AUX_FLT")
		)
		(pad "2" smd rect
			(at 0.889 0)
			(size 1.016 1.27)
			(layers "F.Cu" "F.Mask" "F.Paste")
			(net "GND")
		)
	)
	(footprint ""
		(layer "F.Cu")
		(at 51.816 -76.3524 180)
		(property "Reference" "U54"
			(at 1.0414 -2.23647 0)
			(unlocked yes)
			(layer "F.SilkS")
			(effects
				(font
					(size 0.7874 0.5842)
					(thickness 0.1524)
				)
				(justify left)
			)
		)
		(property "Value" ""
			(at 0 0 180)
			(layer "F.Fab")
			(effects
				(font
					(size 1.27 1.27)
				)
			)
		)
		(duplicate_pad_numbers_are_jumpers no)
		(fp_line
			(start 1.207008 1.549908)
			(end 1.207008 -1.549908)
			(stroke
				(width 0.1524)
				(type default)
			)
			(layer "F.SilkS")
		)
		(fp_line
			(start 1.207008 -1.549908)
			(end 0.762508 -1.549908)
			(stroke
				(width 0.1524)
				(type default)
			)
			(layer "F.SilkS")
		)
		(fp_line
			(start 0.762508 -1.549908)
			(end 0 -0.635)
			(stroke
				(width 0.1524)
				(type default)
			)
			(layer "F.SilkS")
		)
		(fp_line
			(start 0 -0.635)
			(end -0.762508 -1.549908)
			(stroke
				(width 0.1524)
				(type default)
			)
			(layer "F.SilkS")
		)
		(fp_line
			(start -0.762508 -1.549908)
			(end -1.207008 -1.549908)
			(stroke
				(width 0.1524)
				(type default)
			)
			(layer "F.SilkS")
		)
		(fp_line
			(start -1.207008 1.549908)
			(end 1.207008 1.549908)
			(stroke
				(width 0.1524)
				(type default)
			)
			(layer "F.SilkS")
		)
		(fp_line
			(start -1.207008 -1.549908)
			(end -1.207008 1.549908)
			(stroke
				(width 0.1524)
				(type default)
			)
			(layer "F.SilkS")
		)
		(fp_poly
			(pts
				(xy -2.699258 -2.852166) (xy -3.41757 -2.1336) (xy -2.340102 -1.774444)
			)
			(stroke
				(width 0)
				(type default)
			)
			(fill yes)
			(layer "F.SilkS")
		)
		(fp_line
			(start 1.549908 1.549908)
			(end 1.549908 -1.549908)
			(stroke
				(width 0.1)
				(type default)
			)
			(layer "F.Fab")
		)
		(fp_line
			(start 1.549908 -1.549908)
			(end -1.549908 -1.549908)
			(stroke
				(width 0.1)
				(type default)
			)
			(layer "F.Fab")
		)
		(fp_line
			(start -1.549908 1.549908)
			(end 1.549908 1.549908)
			(stroke
				(width 0.1)
				(type default)
			)
			(layer "F.Fab")
		)
		(fp_line
			(start -1.549908 -1.549908)
			(end -1.549908 1.549908)
			(stroke
				(width 0.1)
				(type default)
			)
			(layer "F.Fab")
		)
		(fp_poly
			(pts
				(xy -3.4036 -1.53289) (xy -3.4036 -0.51689) (xy -2.3876 -1.02489)
			)
			(stroke
				(width 0)
				(type default)
			)
			(fill yes)
			(layer "F.Fab")
		)
		(pad "1" smd rect
			(at -1.774952 -1.02489 90)
			(size 0.508 0.8636)
			(layers "F.Cu" "F.Mask" "F.Paste")
			(net "FLASH_LATCH_CP")
		)
		(pad "2" smd rect
			(at -1.774952 -0.32512 90)
			(size 0.4064 0.8636)
			(layers "F.Cu" "F.Mask" "F.Paste")
			(net "FLASH_LATCH_D")
		)
		(pad "3" smd rect
			(at -1.774952 0.32512 90)
			(size 0.4064 0.8636)
			(layers "F.Cu" "F.Mask" "F.Paste")
			(net "FLASH_LATCH_Q_N_R")
		)
		(pad "4" smd rect
			(at -1.774952 1.02489 90)
			(size 0.508 0.8636)
			(layers "F.Cu" "F.Mask" "F.Paste")
			(net "GND")
		)
		(pad "5" smd rect
			(at 1.774952 1.02489 90)
			(size 0.508 0.8636)
			(layers "F.Cu" "F.Mask" "F.Paste")
			(net "NC_U54_P1")
		)
		(pad "6" smd rect
			(at 1.774952 0.32512 90)
			(size 0.4064 0.8636)
			(layers "F.Cu" "F.Mask" "F.Paste")
			(net "RD_N")
		)
		(pad "7" smd rect
			(at 1.774952 -0.32512 90)
			(size 0.4064 0.8636)
			(layers "F.Cu" "F.Mask" "F.Paste")
			(net "FM_FLASH_LATCH_N")
		)
		(pad "8" smd rect
			(at 1.774952 -1.02489 90)
			(size 0.508 0.8636)
			(layers "F.Cu" "F.Mask" "F.Paste")
			(net "P3V3_AUX")
		)
	)
	(footprint ""
		(layer "F.Cu")
		(at 9.271 -85.852)
		(property "Reference" "R711"
			(at 0 0 0)
			(layer "F.SilkS")
			(hide yes)
			(effects
				(font
					(size 1.27 1.27)
				)
			)
		)
		(property "Value" ""
			(at 0 0 0)
			(layer "F.Fab")
			(effects
				(font
					(size 1.27 1.27)
				)
			)
		)
		(duplicate_pad_numbers_are_jumpers no)
		(fp_line
			(start -0.7874 -0.4064)
			(end 0.7874 -0.4064)
			(stroke
				(width 0.1524)
				(type default)
			)
			(layer "F.SilkS")
		)
		(fp_line
			(start -0.7874 0.4064)
			(end -0.7874 -0.4064)
			(stroke
				(width 0.1524)
				(type default)
			)
			(layer "F.SilkS")
		)
		(fp_line
			(start 0.7874 -0.4064)
			(end 0.7874 0.4064)
			(stroke
				(width 0.1524)
				(type default)
			)
			(layer "F.SilkS")
		)
		(fp_line
			(start 0.7874 0.4064)
			(end -0.7874 0.4064)
			(stroke
				(width 0.1524)
				(type default)
			)
			(layer "F.SilkS")
		)
		(fp_line
			(start -0.67945 -0.305054)
			(end -0.12065 -0.305054)
			(stroke
				(width 0.1)
				(type default)
			)
			(layer "F.Fab")
		)
		(fp_line
			(start -0.67945 0.3048)
			(end -0.67945 -0.305054)
			(stroke
				(width 0.1)
				(type default)
			)
			(layer "F.Fab")
		)
		(fp_line
			(start -0.12065 -0.305054)
			(end -0.12065 -0.2794)
			(stroke
				(width 0.1)
				(type default)
			)
			(layer "F.Fab")
		)
		(fp_line
			(start -0.12065 -0.2794)
			(end 0.12065 -0.2794)
			(stroke
				(width 0.1)
				(type default)
			)
			(layer "F.Fab")
		)
		(fp_line
			(start -0.12065 0.2794)
			(end -0.12065 0.3048)
			(stroke
				(width 0.1)
				(type default)
			)
			(layer "F.Fab")
		)
		(fp_line
			(start -0.12065 0.3048)
			(end -0.67945 0.3048)
			(stroke
				(width 0.1)
				(type default)
			)
			(layer "F.Fab")
		)
		(fp_line
			(start 0.120396 0.2794)
			(end -0.12065 0.2794)
			(stroke
				(width 0.1)
				(type default)
			)
			(layer "F.Fab")
		)
		(fp_line
			(start 0.120396 0.3048)
			(end 0.120396 0.2794)
			(stroke
				(width 0.1)
				(type default)
			)
			(layer "F.Fab")
		)
		(fp_line
			(start 0.12065 -0.3048)
			(end 0.67945 -0.3048)
			(stroke
				(width 0.1)
				(type default)
			)
			(layer "F.Fab")
		)
		(fp_line
			(start 0.12065 -0.2794)
			(end 0.12065 -0.3048)
			(stroke
				(width 0.1)
				(type default)
			)
			(layer "F.Fab")
		)
		(fp_line
			(start 0.67945 -0.3048)
			(end 0.67945 0.3048)
			(stroke
				(width 0.1)
				(type default)
			)
			(layer "F.Fab")
		)
		(fp_line
			(start 0.67945 0.3048)
			(end 0.120396 0.3048)
			(stroke
				(width 0.1)
				(type default)
			)
			(layer "F.Fab")
		)
		(pad "1" smd circle
			(at -0.40005 0)
			(size 0 0)
			(layers "F.Cu" "F.Mask" "F.Paste")
			(net "PWRGD_PSU_AC_PWROK")
		)
		(pad "2" smd circle
			(at 0.40005 0)
			(size 0 0)
			(layers "F.Cu" "F.Mask" "F.Paste")
			(net "PWRGD_P1V0_AUX_DELAY")
		)
	)
	(footprint ""
		(layer "F.Cu")
		(at 42.346626 -18.1864 90)
		(property "Reference" "U27"
			(at -0.8509 2.015744 90)
			(unlocked yes)
			(layer "F.SilkS")
			(effects
				(font
					(size 0.7874 0.5842)
					(thickness 0.1524)
				)
				(justify left)
			)
		)
		(property "Value" ""
			(at 0 0 90)
			(layer "F.Fab")
			(effects
				(font
					(size 1.27 1.27)
				)
			)
		)
		(duplicate_pad_numbers_are_jumpers no)
		(fp_line
			(start 0.791464 -1.287526)
			(end -0.791464 -1.287526)
			(stroke
				(width 0.1524)
				(type default)
			)
			(layer "F.SilkS")
		)
		(fp_line
			(start -0.791464 -1.287526)
			(end -0.791464 -1.147826)
			(stroke
				(width 0.1524)
				(type default)
			)
			(layer "F.SilkS")
		)
		(fp_line
			(start 0.791464 -1.147826)
			(end 0.791464 -1.287526)
			(stroke
				(width 0.1524)
				(type default)
			)
			(layer "F.SilkS")
		)
		(fp_line
			(start -0.791464 -0.385826)
			(end -0.791464 0.325374)
			(stroke
				(width 0.1524)
				(type default)
			)
			(layer "F.SilkS")
		)
		(fp_line
			(start 0.791464 0.401574)
			(end 0.791464 -0.335026)
			(stroke
				(width 0.1524)
				(type default)
			)
			(layer "F.SilkS")
		)
		(fp_line
			(start -0.791464 1.112774)
			(end -0.791464 1.287526)
			(stroke
				(width 0.1524)
				(type default)
			)
			(layer "F.SilkS")
		)
		(fp_line
			(start 0.791464 1.287526)
			(end 0.791464 1.112774)
			(stroke
				(width 0.1524)
				(type default)
			)
			(layer "F.SilkS")
		)
		(fp_line
			(start -0.791464 1.287526)
			(end 0.791464 1.287526)
			(stroke
				(width 0.1524)
				(type default)
			)
			(layer "F.SilkS")
		)
		(fp_poly
			(pts
				(xy -1.006602 -2.022602) (xy -1.365758 -1.663446) (xy -0.827024 -1.483868)
			)
			(stroke
				(width 0)
				(type default)
			)
			(fill yes)
			(layer "F.SilkS")
		)
		(fp_line
			(start 0.537464 -1.287526)
			(end -0.537464 -1.287526)
			(stroke
				(width 0.1)
				(type default)
			)
			(layer "F.Fab")
		)
		(fp_line
			(start -0.537464 -1.287526)
			(end -0.537464 1.287526)
			(stroke
				(width 0.1)
				(type default)
			)
			(layer "F.Fab")
		)
		(fp_line
			(start 0.537464 1.287526)
			(end 0.537464 -1.287526)
			(stroke
				(width 0.1)
				(type default)
			)
			(layer "F.Fab")
		)
		(fp_line
			(start -0.537464 1.287526)
			(end 0.537464 1.287526)
			(stroke
				(width 0.1)
				(type default)
			)
			(layer "F.Fab")
		)
		(fp_poly
			(pts
				(xy -1.651 -1.253998) (xy -1.651 -0.745998) (xy -1.143 -0.999998)
			)
			(stroke
				(width 0)
				(type default)
			)
			(fill yes)
			(layer "F.Fab")
		)
		(pad "1" smd rect
			(at -0.387604 -0.999998 180)
			(size 0.254 0.635)
			(layers "F.Cu" "F.Mask" "F.Paste")
			(net "USB3_01_FB_TXP")
		)
		(pad "2" smd rect
			(at -0.387604 -0.499872 180)
			(size 0.254 0.635)
			(layers "F.Cu" "F.Mask" "F.Paste")
			(net "USB3_01_FB_TXN")
		)
		(pad "3" smd rect
			(at -0.350012 0 180)
			(size 0.4572 0.6858)
			(layers "F.Cu" "F.Mask" "F.Paste")
			(net "GND")
		)
		(pad "4" smd rect
			(at -0.387604 0.499872 180)
			(size 0.254 0.635)
			(layers "F.Cu" "F.Mask" "F.Paste")
			(net "USB3_01_FB_RXP")
		)
		(pad "5" smd rect
			(at -0.387604 0.999998 180)
			(size 0.254 0.635)
			(layers "F.Cu" "F.Mask" "F.Paste")
			(net "USB3_01_FB_RXN")
		)
		(pad "6" smd rect
			(at 0.387604 0.999998 180)
			(size 0.254 0.635)
			(layers "F.Cu" "F.Mask" "F.Paste")
			(net "USB3_01_FB_RXN")
		)
		(pad "7" smd rect
			(at 0.387604 0.499872 180)
			(size 0.254 0.635)
			(layers "F.Cu" "F.Mask" "F.Paste")
			(net "USB3_01_FB_RXP")
		)
		(pad "8" smd rect
			(at 0.412496 0 180)
			(size 0.4572 0.5842)
			(layers "F.Cu" "F.Mask" "F.Paste")
			(net "GND")
		)
		(pad "9" smd rect
			(at 0.387604 -0.499872 180)
			(size 0.254 0.635)
			(layers "F.Cu" "F.Mask" "F.Paste")
			(net "USB3_01_FB_TXN")
		)
		(pad "10" smd rect
			(at 0.387604 -0.999998 180)
			(size 0.254 0.635)
			(layers "F.Cu" "F.Mask" "F.Paste")
			(net "USB3_01_FB_TXP")
		)
	)
)
